(kicad_pcb
	(version 20221018)
	(generator pcbnew)
	(general
    (thickness 0.908)
  )
	(paper "A4")
	(title_block
    (title "HDMI-MIPI Bridge")
    (date "2024-04-24")
    (rev "1.3.2")
		(comment 9 "footprints 63-70 of 121")
	)
	(layers
    (0 "F.Cu" signal)
    (1 "In1.Cu" signal)
    (2 "In2.Cu" signal)
    (31 "B.Cu" signal)
    (32 "B.Adhes" user "B.Adhesive")
    (33 "F.Adhes" user "F.Adhesive")
    (34 "B.Paste" user)
    (35 "F.Paste" user)
    (36 "B.SilkS" user "B.Silkscreen")
    (37 "F.SilkS" user "F.Silkscreen")
    (38 "B.Mask" user)
    (39 "F.Mask" user)
    (40 "Dwgs.User" user "User.Drawings")
    (41 "Cmts.User" user "User.Comments")
    (42 "Eco1.User" user "User.Eco1")
    (43 "Eco2.User" user "User.Eco2")
    (44 "Edge.Cuts" user)
    (45 "Margin" user)
    (46 "B.CrtYd" user "B.Courtyard")
    (47 "F.CrtYd" user "F.Courtyard")
    (48 "B.Fab" user)
    (49 "F.Fab" user)
  )
	(footprint "antmicro-footprints:C_0603_1608Metric" (layer "F.Cu")
    (at 147.35 113.05 180)
    (descr "Capacitor SMD 0603")
    (tags "capacitor 0603")
    (property "Author" "Antmicro")
    (property "Dielectric" "template_dielectric")
    (property "License" "Apache-2.0")
    (property "MPN" "GRM188R61A106KE69D")
    (property "Manufacturer" "Murata")
    (property "Public" "False")
    (property "Sheetfile" "channel1.kicad_sch")
    (property "Sheetname" "Channel 1")
    (property "Val" "10u")
    (property "Voltage" "")
    (property "ki_description" "SMD Multilayer Ceramic Capacitor, 10 µF, 10 V, 0603 [1608 Metric], ± 10%, X5R, GRM Series")
    (property "ki_keywords" "0603, SMT, CAPACITOR, PASSIVE, CERAMIC, MLCC")
    (attr smd)
    (fp_text reference "C19" (at -3.21 -0.69) (layer "F.SilkS")
        (effects (font (size 0.65 0.65) (thickness 0.13)) (justify right bottom))
    )
    (fp_text value "C_10u_0603" (at 0 1.6) (layer "F.Fab")
        (effects (font (size 0.65 0.65) (thickness 0.13)) (justify right bottom))
    )
    (fp_text user "License: Apache-2.0" (at -1.682 5.895) (layer "F.Fab") hide
        (effects (font (size 0.7 0.7) (thickness 0.15)) (justify right bottom))
    )
    (fp_text user "Author: Antmicro" (at -1.682 4.894) (layer "F.Fab") hide
        (effects (font (size 0.7 0.7) (thickness 0.15)) (justify right bottom))
    )
    (fp_text user "${REFERENCE}" (at -1.682 3.895) (layer "F.Fab") hide
        (effects (font (size 0.7 0.7) (thickness 0.15)) (justify right bottom))
    )
    (fp_line (start -0.15 -0.4) (end 0.15 -0.4)
      (stroke (width 0.15) (type solid)) (layer "F.SilkS"))
    (fp_line (start -0.15 0.4) (end 0.15 0.4)
      (stroke (width 0.15) (type solid)) (layer "F.SilkS"))
    (fp_rect (start -1.25 -0.65) (end 1.25 0.65)
      (stroke (width 0.05) (type solid)) (fill none) (layer "F.CrtYd"))
    (fp_rect (start -0.8 -0.4) (end 0.8 0.4)
      (stroke (width 0.15) (type solid)) (fill none) (layer "F.Fab"))
    (pad "1" smd roundrect (at -0.7 0 180) (size 0.8 1) (layers "F.Cu" "F.Paste" "F.Mask") (roundrect_rratio 0.2)
      (net 2 "GND") (pintype "passive"))
    (pad "2" smd roundrect (at 0.7 0 180) (size 0.8 1) (layers "F.Cu" "F.Paste" "F.Mask") (roundrect_rratio 0.2)
      (net 11 "CH1_2V5") (pintype "passive"))
  )
	(footprint "antmicro-footprints:R_0402_1005Metric" (layer "F.Cu")
    (at 163.25 105.85 180)
    (descr "Resistor SMD 0402")
    (tags "resistor SMD 0402")
    (property "Author" "Antmicro")
    (property "License" "Apache-2.0")
    (property "MPN" "CR0402-FX-2001GLF")
    (property "Manufacturer" "Bourns")
    (property "Public" "False")
    (property "Sheetfile" "channel2.kicad_sch")
    (property "Sheetname" "Channel 2")
    (property "Tolerance" "1%")
    (property "Val" "2k")
    (property "ki_description" "SMD Chip Resistor, 2 kohm, ± 1%, 62.5 mW, 0402 [1005 Metric], Thick Film, General Purpose")
    (property "ki_keywords" "0402, SMT, RESISTOR, PASSIVE")
    (attr smd)
    (fp_text reference "R17" (at 2.88 -0.48 180) (layer "F.SilkS")
        (effects (font (size 0.65 0.65) (thickness 0.13)) (justify left bottom))
    )
    (fp_text value "R_2k_0402" (at 0 1.4 180) (layer "F.Fab")
        (effects (font (size 0.65 0.65) (thickness 0.13)) (justify left bottom))
    )
    (fp_text user "${REFERENCE}" (at -0.95 3.168 180) (layer "F.Fab") hide
        (effects (font (size 0.7 0.7) (thickness 0.15)) (justify left bottom))
    )
    (fp_text user "Author: Antmicro" (at -0.95 4.169 180) (layer "F.Fab") hide
        (effects (font (size 0.7 0.7) (thickness 0.15)) (justify left bottom))
    )
    (fp_text user "License: Apache-2.0" (at -0.95 5.169 180) (layer "F.Fab") hide
        (effects (font (size 0.7 0.7) (thickness 0.15)) (justify left bottom))
    )
    (fp_rect (start -0.925 -0.47) (end 0.925 0.47)
      (stroke (width 0.05) (type default)) (fill none) (layer "F.CrtYd"))
    (fp_rect (start -0.5 -0.25) (end 0.5 0.25)
      (stroke (width 0.15) (type solid)) (fill none) (layer "F.Fab"))
    (pad "1" smd roundrect (at -0.48 0 180) (size 0.59 0.64) (layers "F.Cu" "F.Paste" "F.Mask") (roundrect_rratio 0.25)
      (net 114 "Net-(U4B-REXT)") (pintype "passive"))
    (pad "2" smd roundrect (at 0.48 0 180) (size 0.59 0.64) (layers "F.Cu" "F.Paste" "F.Mask") (roundrect_rratio 0.25)
      (net 108 "/Channel 2/CH2_AVDD33") (pintype "passive"))
  )
	(footprint "antmicro-footprints:FB_0805_2012Metric" (layer "F.Cu")
    (at 142.6 108.7 90)
    (descr "FERRITE BEAD 0805")
    (tags "FERRITE BEAD 0805")
    (property "Author" "Antmicro")
    (property "Current" "")
    (property "License" "Apache-2.0")
    (property "MPN" "742792096")
    (property "Manufacturer" "Würth Elektronik")
    (property "Public" "False")
    (property "Sheetfile" "channel1.kicad_sch")
    (property "Sheetname" "Channel 1")
    (property "Val" "1kZ/0.8A")
    (property "ki_description" "Ferrite Beads WE-CBF 0805 100MHz 1kOhm 1A, High Current")
    (property "ki_keywords" "FERRITE BEAD, PASSIVE")
    (attr smd)
    (fp_text reference "FB3" (at -2.5 1.7 90) (layer "F.SilkS")
        (effects (font (size 0.65 0.65) (thickness 0.13)) (justify left bottom))
    )
    (fp_text value "FB_1kZ_0.8A_WE-CBF_0805" (at 0 1.8 90) (layer "F.Fab")
        (effects (font (size 0.65 0.65) (thickness 0.13)) (justify left bottom))
    )
    (fp_text user "Author: Antmicro" (at -1.9 4.4 90) (layer "F.Fab") hide
        (effects (font (size 0.7 0.7) (thickness 0.15)) (justify left bottom))
    )
    (fp_text user "License: Apache-2.0" (at -1.9 5.75 90) (layer "F.Fab") hide
        (effects (font (size 0.7 0.7) (thickness 0.15)) (justify left bottom))
    )
    (fp_text user "${REFERENCE}" (at -1.9 3.1 90) (layer "F.Fab") hide
        (effects (font (size 0.7 0.7) (thickness 0.15)) (justify left bottom))
    )
    (fp_line (start -0.319 0.698) (end 0.281 0.698)
      (stroke (width 0.15) (type solid)) (layer "F.SilkS"))
    (fp_line (start -0.299 -0.698) (end 0.299 -0.698)
      (stroke (width 0.15) (type solid)) (layer "F.SilkS"))
    (fp_rect (start 1.95 -0.9) (end -1.95 0.9)
      (stroke (width 0.05) (type default)) (fill none) (layer "F.CrtYd"))
    (fp_line (start -0.948 -0.681) (end 0.948 -0.681)
      (stroke (width 0.15) (type solid)) (layer "F.Fab"))
    (fp_line (start -0.948 -0.676) (end -0.948 0.676)
      (stroke (width 0.15) (type solid)) (layer "F.Fab"))
    (fp_line (start -0.948 0.681) (end 0.948 0.681)
      (stroke (width 0.15) (type solid)) (layer "F.Fab"))
    (fp_line (start 0.948 -0.676) (end 0.948 0.676)
      (stroke (width 0.15) (type solid)) (layer "F.Fab"))
    (pad "1" smd roundrect (at -1.1 0 90) (size 1.2 1.3) (layers "F.Cu" "F.Paste" "F.Mask") (roundrect_rratio 0.25)
      (net 6 "Net-(C5-Pad1)") (pintype "passive"))
    (pad "2" smd roundrect (at 1.1 0 90) (size 1.2 1.3) (layers "F.Cu" "F.Paste" "F.Mask") (roundrect_rratio 0.25)
      (net 12 "CH1_1V2") (pintype "passive"))
  )
	(footprint "antmicro-footprints:R_0603_1608Metric" (layer "F.Cu")
    (at 144.9 101.85)
    (descr "Resistor SMD 0603")
    (tags "resistor SMD 0603")
    (property "Author" "Antmicro")
    (property "Current" "1A")
    (property "License" "Apache-2.0")
    (property "MPN" "CR0603-J/-000ELF")
    (property "Manufacturer" "Bourns")
    (property "Public" "False")
    (property "Sheetfile" "channel1.kicad_sch")
    (property "Sheetname" "Channel 1")
    (property "Tolerance" "")
    (property "Val" "0R")
    (property "ki_description" "Zero Ohm Resistor, Jumper, 0603 [1608 Metric], Thick Film, 100 mW, 1 A, Surface Mount Device, CR")
    (property "ki_keywords" "0603, SMT, RESISTOR, PASSIVE")
    (attr smd)
    (fp_text reference "R1" (at 1 0.35) (layer "F.SilkS")
        (effects (font (size 0.7 0.7) (thickness 0.15)) (justify left bottom))
    )
    (fp_text value "R_0R_0603" (at 0 1.6) (layer "F.Fab")
        (effects (font (size 0.7 0.7) (thickness 0.15)) (justify left bottom))
    )
    (fp_text user "${REFERENCE}" (at -1.25 3.898) (layer "F.Fab") hide
        (effects (font (size 0.7 0.7) (thickness 0.15)) (justify left bottom))
    )
    (fp_text user "Author: Antmicro" (at -1.25 4.9) (layer "F.Fab") hide
        (effects (font (size 0.7 0.7) (thickness 0.15)) (justify left bottom))
    )
    (fp_text user "License: Apache-2.0" (at -1.25 5.9) (layer "F.Fab") hide
        (effects (font (size 0.7 0.7) (thickness 0.15)) (justify left bottom))
    )
    (fp_line (start -0.15 -0.4) (end 0.15 -0.4)
      (stroke (width 0.15) (type solid)) (layer "F.SilkS"))
    (fp_line (start -0.15 0.4) (end 0.15 0.4)
      (stroke (width 0.15) (type solid)) (layer "F.SilkS"))
    (fp_rect (start -1.25 -0.65) (end 1.25 0.65)
      (stroke (width 0.05) (type solid)) (fill none) (layer "F.CrtYd"))
    (fp_rect (start -0.8 -0.4) (end 0.8 0.4)
      (stroke (width 0.15) (type solid)) (fill none) (layer "F.Fab"))
    (pad "1" smd roundrect (at -0.7 0) (size 0.8 1) (layers "F.Cu" "F.Paste" "F.Mask") (roundrect_rratio 0.2)
      (net 86 "/Channel 1/HDMI1_POWER") (pintype "passive"))
    (pad "2" smd roundrect (at 0.7 0) (size 0.8 1) (layers "F.Cu" "F.Paste" "F.Mask") (roundrect_rratio 0.2)
      (net 87 "/Channel 1/HDMI1_HPD") (pintype "passive"))
  )
	(footprint "antmicro-footprints:C_0603_1608Metric" (layer "F.Cu")
    (at 165.5 119.95 -90)
    (descr "Capacitor SMD 0603")
    (tags "capacitor 0603")
    (property "Author" "Antmicro")
    (property "Dielectric" "template_dielectric")
    (property "License" "Apache-2.0")
    (property "MPN" "GRM188R61A106KE69D")
    (property "Manufacturer" "Murata")
    (property "Public" "False")
    (property "Sheetfile" "channel2.kicad_sch")
    (property "Sheetname" "Channel 2")
    (property "Val" "10u")
    (property "Voltage" "")
    (property "ki_description" "SMD Multilayer Ceramic Capacitor, 10 µF, 10 V, 0603 [1608 Metric], ± 10%, X5R, GRM Series")
    (property "ki_keywords" "0603, SMT, CAPACITOR, PASSIVE, CERAMIC, MLCC")
    (attr smd)
    (fp_text reference "C41" (at 1.15 -0.2 90) (layer "F.SilkS")
        (effects (font (size 0.65 0.65) (thickness 0.13)) (justify right bottom))
    )
    (fp_text value "C_10u_0603" (at 0 1.6 90) (layer "F.Fab")
        (effects (font (size 0.65 0.65) (thickness 0.13)) (justify right bottom))
    )
    (fp_text user "License: Apache-2.0" (at -1.682 5.895 90) (layer "F.Fab") hide
        (effects (font (size 0.7 0.7) (thickness 0.15)) (justify right bottom))
    )
    (fp_text user "Author: Antmicro" (at -1.682 4.894 90) (layer "F.Fab") hide
        (effects (font (size 0.7 0.7) (thickness 0.15)) (justify right bottom))
    )
    (fp_text user "${REFERENCE}" (at -1.682 3.895 90) (layer "F.Fab") hide
        (effects (font (size 0.7 0.7) (thickness 0.15)) (justify right bottom))
    )
    (fp_line (start -0.15 -0.4) (end 0.15 -0.4)
      (stroke (width 0.15) (type solid)) (layer "F.SilkS"))
    (fp_line (start -0.15 0.4) (end 0.15 0.4)
      (stroke (width 0.15) (type solid)) (layer "F.SilkS"))
    (fp_rect (start -1.25 -0.65) (end 1.25 0.65)
      (stroke (width 0.05) (type solid)) (fill none) (layer "F.CrtYd"))
    (fp_rect (start -0.8 -0.4) (end 0.8 0.4)
      (stroke (width 0.15) (type solid)) (fill none) (layer "F.Fab"))
    (pad "1" smd roundrect (at -0.7 0 270) (size 0.8 1) (layers "F.Cu" "F.Paste" "F.Mask") (roundrect_rratio 0.2)
      (net 2 "GND") (pintype "passive"))
    (pad "2" smd roundrect (at 0.7 0 270) (size 0.8 1) (layers "F.Cu" "F.Paste" "F.Mask") (roundrect_rratio 0.2)
      (net 9 "+3V3") (pintype "passive"))
  )
	(footprint "antmicro-footprints:R_0402_1005Metric" (layer "F.Cu")
    (at 144.1 108.085 -90)
    (descr "Resistor SMD 0402")
    (tags "resistor SMD 0402")
    (property "Author" "Antmicro")
    (property "License" "Apache-2.0")
    (property "MPN" "CR0402-FX-1002GLF")
    (property "Manufacturer" "Bourns")
    (property "Public" "False")
    (property "Sheetfile" "channel1.kicad_sch")
    (property "Sheetname" "Channel 1")
    (property "Tolerance" "1%")
    (property "Val" "10k")
    (property "ki_description" "SMD Chip Resistor, 10 kohm, ± 1%, 62.5 mW, 0402 [1005 Metric], Thick Film, General Purpose")
    (property "ki_keywords" "0402, SMT, RESISTOR, PASSIVE")
    (attr smd)
    (fp_text reference "R10" (at -1.035 -1.66 -90) (layer "F.SilkS")
        (effects (font (size 0.65 0.65) (thickness 0.13)) (justify left bottom))
    )
    (fp_text value "R_10k_0402" (at 0 1.4 -90) (layer "F.Fab")
        (effects (font (size 0.65 0.65) (thickness 0.13)) (justify left bottom))
    )
    (fp_text user "License: Apache-2.0" (at -0.95 5.169 -90) (layer "F.Fab") hide
        (effects (font (size 0.7 0.7) (thickness 0.15)) (justify left bottom))
    )
    (fp_text user "Author: Antmicro" (at -0.95 4.169 -90) (layer "F.Fab") hide
        (effects (font (size 0.7 0.7) (thickness 0.15)) (justify left bottom))
    )
    (fp_text user "${REFERENCE}" (at -0.95 3.168 -90) (layer "F.Fab") hide
        (effects (font (size 0.7 0.7) (thickness 0.15)) (justify left bottom))
    )
    (fp_rect (start -0.925 -0.47) (end 0.925 0.47)
      (stroke (width 0.05) (type default)) (fill none) (layer "F.CrtYd"))
    (fp_rect (start -0.5 -0.25) (end 0.5 0.25)
      (stroke (width 0.15) (type solid)) (fill none) (layer "F.Fab"))
    (pad "1" smd roundrect (at -0.48 0 270) (size 0.59 0.64) (layers "F.Cu" "F.Paste" "F.Mask") (roundrect_rratio 0.25)
      (net 105 "/Channel 1/HDMI1_DDC_SCL_3V3") (pintype "passive"))
    (pad "2" smd roundrect (at 0.48 0 270) (size 0.59 0.64) (layers "F.Cu" "F.Paste" "F.Mask") (roundrect_rratio 0.25)
      (net 9 "+3V3") (pintype "passive"))
  )
	(footprint "antmicro-footprints:C_0603_1608Metric" (layer "F.Cu")
    (at 145.2 115.7 -90)
    (descr "Capacitor SMD 0603")
    (tags "capacitor 0603")
    (property "Author" "Antmicro")
    (property "Dielectric" "template_dielectric")
    (property "License" "Apache-2.0")
    (property "MPN" "GRM188R61A106KE69D")
    (property "Manufacturer" "Murata")
    (property "Public" "False")
    (property "Sheetfile" "channel1.kicad_sch")
    (property "Sheetname" "Channel 1")
    (property "Val" "10u")
    (property "Voltage" "")
    (property "ki_description" "SMD Multilayer Ceramic Capacitor, 10 µF, 10 V, 0603 [1608 Metric], ± 10%, X5R, GRM Series")
    (property "ki_keywords" "0603, SMT, CAPACITOR, PASSIVE, CERAMIC, MLCC")
    (attr smd)
    (fp_text reference "C20" (at -3.1 -0.3 90) (layer "F.SilkS")
        (effects (font (size 0.65 0.65) (thickness 0.13)) (justify right bottom))
    )
    (fp_text value "C_10u_0603" (at 0 1.6 90) (layer "F.Fab")
        (effects (font (size 0.65 0.65) (thickness 0.13)) (justify right bottom))
    )
    (fp_text user "Author: Antmicro" (at -1.682 4.894 90) (layer "F.Fab") hide
        (effects (font (size 0.7 0.7) (thickness 0.15)) (justify right bottom))
    )
    (fp_text user "License: Apache-2.0" (at -1.682 5.895 90) (layer "F.Fab") hide
        (effects (font (size 0.7 0.7) (thickness 0.15)) (justify right bottom))
    )
    (fp_text user "${REFERENCE}" (at -1.682 3.895 90) (layer "F.Fab") hide
        (effects (font (size 0.7 0.7) (thickness 0.15)) (justify right bottom))
    )
    (fp_line (start -0.15 -0.4) (end 0.15 -0.4)
      (stroke (width 0.15) (type solid)) (layer "F.SilkS"))
    (fp_line (start -0.15 0.4) (end 0.15 0.4)
      (stroke (width 0.15) (type solid)) (layer "F.SilkS"))
    (fp_rect (start -1.25 -0.65) (end 1.25 0.65)
      (stroke (width 0.05) (type solid)) (fill none) (layer "F.CrtYd"))
    (fp_rect (start -0.8 -0.4) (end 0.8 0.4)
      (stroke (width 0.15) (type solid)) (fill none) (layer "F.Fab"))
    (pad "1" smd roundrect (at -0.7 0 270) (size 0.8 1) (layers "F.Cu" "F.Paste" "F.Mask") (roundrect_rratio 0.2)
      (net 2 "GND") (pintype "passive"))
    (pad "2" smd roundrect (at 0.7 0 270) (size 0.8 1) (layers "F.Cu" "F.Paste" "F.Mask") (roundrect_rratio 0.2)
      (net 12 "CH1_1V2") (pintype "passive"))
  )
	(footprint "antmicro-footprints:SOT-23-5" (layer "F.Cu")
    (at 148.25 115.95 90)
    (property "Author" "Antmicro")
    (property "License" "Apache-2.0")
    (property "MPN" "TLV73325PDBVT")
    (property "Manufacturer" "Texas Instruments")
    (property "Sheetfile" "channel1.kicad_sch")
    (property "Sheetname" "Channel 1")
    (property "ki_description" "Linear voltage regulator")
    (property "ki_keywords" "SMT, PMIC, IC, LDO, LINEAR, VOLTAGE, REGULATOR")
    (attr smd)
    (fp_text reference "IC1" (at -0.81 2.73 90) (layer "F.SilkS")
        (effects (font (size 0.65 0.65) (thickness 0.13)) (justify left bottom))
    )
    (fp_text value "TLV73325PDBVT" (at 0.002 2.799 90) (layer "F.Fab")
        (effects (font (size 0.65 0.65) (thickness 0.13)) (justify left bottom))
    )
    (fp_text user "${REFERENCE}" (at -1.898 4.299 90) (layer "F.Fab") hide
        (effects (font (size 0.7 0.7) (thickness 0.15)) (justify left bottom))
    )
    (fp_text user "Author: Antmicro" (at -1.898 5.499 90) (layer "F.Fab") hide
        (effects (font (size 0.7 0.7) (thickness 0.15)) (justify left bottom))
    )
    (fp_text user "License: Apache-2.0" (at -1.898 6.7 90) (layer "F.Fab") hide
        (effects (font (size 0.7 0.7) (thickness 0.15)) (justify left bottom))
    )
    (fp_line (start -0.85 1.6) (end -0.85 1.301)
      (stroke (width 0.15) (type solid)) (layer "F.SilkS"))
    (fp_line (start -0.8 -1.6) (end -0.8 -1.3)
      (stroke (width 0.15) (type solid)) (layer "F.SilkS"))
    (fp_line (start -0.8 -1.6) (end -0.5 -1.6)
      (stroke (width 0.15) (type solid)) (layer "F.SilkS"))
    (fp_line (start -0.55 1.6) (end -0.85 1.6)
      (stroke (width 0.15) (type solid)) (layer "F.SilkS"))
    (fp_line (start 0.8 -1.6) (end 0.5 -1.6)
      (stroke (width 0.15) (type solid)) (layer "F.SilkS"))
    (fp_line (start 0.8 -1.3) (end 0.8 -1.6)
      (stroke (width 0.15) (type solid)) (layer "F.SilkS"))
    (fp_line (start 0.8 0.55) (end 0.8 -0.55)
      (stroke (width 0.15) (type solid)) (layer "F.SilkS"))
    (fp_line (start 0.8 1.3) (end 0.8 1.599)
      (stroke (width 0.15) (type solid)) (layer "F.SilkS"))
    (fp_line (start 0.8 1.599) (end 0.549 1.599)
      (stroke (width 0.15) (type solid)) (layer "F.SilkS"))
    (fp_circle (center -1.25 -1.5) (end -1.2 -1.5)
      (stroke (width 0.15) (type solid)) (fill solid) (layer "F.SilkS"))
    (fp_rect (start 1.9 -1.76) (end -1.9 1.75)
      (stroke (width 0.05) (type solid)) (fill none) (layer "F.CrtYd"))
    (fp_line (start -0.398 -1.526) (end -0.874 -1.05)
      (stroke (width 0.15) (type solid)) (layer "F.Fab"))
    (fp_rect (start 0.874 1.523) (end -0.873 -1.525)
      (stroke (width 0.15) (type solid)) (fill none) (layer "F.Fab"))
    (pad "1" smd rect (at -1.351 -0.951) (size 0.55 1) (layers "F.Cu" "F.Paste" "F.Mask")
      (net 9 "+3V3") (pinfunction "VIN") (pintype "power_in"))
    (pad "2" smd rect (at -1.351 0) (size 0.55 1) (layers "F.Cu" "F.Paste" "F.Mask")
      (net 2 "GND") (pinfunction "GND") (pintype "power_in"))
    (pad "3" smd rect (at -1.351 0.949) (size 0.55 1) (layers "F.Cu" "F.Paste" "F.Mask")
      (net 9 "+3V3") (pinfunction "EN") (pintype "input"))
    (pad "4" smd rect (at 1.35 0.949) (size 0.55 1) (layers "F.Cu" "F.Paste" "F.Mask")
      (net 99 "unconnected-(IC1-NC-Pad4)") (pinfunction "NC") (pintype "no_connect"))
    (pad "5" smd rect (at 1.35 -0.951) (size 0.55 1) (layers "F.Cu" "F.Paste" "F.Mask")
      (net 11 "CH1_2V5") (pinfunction "VOUT") (pintype "power_out"))
  )
)
